# S9S_MB_2U (Grand Teton) — schematic netlist excerpt (pin names and nets, part order shuffled) for the footprints in the layout excerpt that follows; sources: Cadence DE-HDL packaged netlist, KiCad conversion of 03242023_DA0F0TMBIJ0_F0T_Motherboard_J_brd_V01_OCP.brd

R2972  Q_RES  10K 1% CHIP  pkg 0402LF  page 195 : A = P1V05_PCH_AUX ; B = FAB_REV_ID2
PR3930  Q_RES  0 5% CHIP  pkg 0402LF  page 301 : A = AGND_HSC ; B = HSC_ADDR

(kicad_pcb
	(version 20260206)
	(generator "pcbnew")
	(generator_version "10.0")
	(general
		(thickness 1.6)
		(legacy_teardrops no)
	)
	(paper "A4")
	(title_block
		(title "03242023_DA0F0TMBIJ0_F0T_Motherboard_J_brd_V01_OCP.brd")
		(comment 1 "Grand Teton / footprints 1087-1088 of 6105")
	)
	(layers
		(0 "F.Cu" signal "TOP")
		(4 "In1.Cu" signal "GND")
		(6 "In2.Cu" signal "IN1")
		(8 "In3.Cu" signal "GND1")
		(10 "In4.Cu" signal "IN2")
		(12 "In5.Cu" signal "GND2")
		(14 "In6.Cu" signal "IN3")
		(16 "In7.Cu" signal "GND3")
		(18 "In8.Cu" signal "VCC")
		(20 "In9.Cu" signal "VCC1")
		(22 "In10.Cu" signal "GND4")
		(24 "In11.Cu" signal "IN4")
		(26 "In12.Cu" signal "GND5")
		(28 "In13.Cu" signal "IN5")
		(30 "In14.Cu" signal "GND6")
		(32 "In15.Cu" signal "IN6")
		(34 "In16.Cu" signal "GND7")
		(2 "B.Cu" signal "BOTTOM")
		(9 "F.Adhes" user "F.Adhesive")
		(11 "B.Adhes" user "B.Adhesive")
		(13 "F.Paste" user "Package Geometry/Pastemask Top")
		(15 "B.Paste" user "Package Geometry/Pastemask Bottom")
		(5 "F.SilkS" user "Ref Des/Silkscreen Top")
		(7 "B.SilkS" user "Ref Des/Silkscreen Bottom")
		(1 "F.Mask" user "Board Geometry/Soldermask Top")
		(3 "B.Mask" user "Board Geometry/Soldermask Bottom")
		(17 "Dwgs.User" user "User.Drawings")
		(19 "Cmts.User" user "User.Comments")
		(21 "Eco1.User" user "User.Eco1")
		(23 "Eco2.User" user "User.Eco2")
		(25 "Edge.Cuts" user "Board Geometry/Outline")
		(27 "Margin" user)
		(31 "F.CrtYd" user "Package Geometry/Place Bound Top")
		(29 "B.CrtYd" user "Package Geometry/Place Bound Bottom")
		(35 "F.Fab" user "Ref Des/Assembly Top")
		(33 "B.Fab" user "Ref Des/Assembly Bottom")
	)
	(footprint ""
		(layer "F.Cu")
		(at 299.02023 -47.288196)
		(property "Reference" "R2972"
			(at 0 0 0)
			(layer "F.SilkS")
			(hide yes)
			(effects
				(font
					(size 1.27 1.27)
				)
			)
		)
		(property "Value" ""
			(at 0 0 0)
			(layer "F.Fab")
			(effects
				(font
					(size 1.27 1.27)
				)
			)
		)
		(duplicate_pad_numbers_are_jumpers no)
		(fp_line
			(start -0.7874 -0.4064)
			(end 0.7874 -0.4064)
			(stroke
				(width 0.1524)
				(type default)
			)
			(layer "F.SilkS")
		)
		(fp_line
			(start -0.7874 0.4064)
			(end -0.7874 -0.4064)
			(stroke
				(width 0.1524)
				(type default)
			)
			(layer "F.SilkS")
		)
		(fp_line
			(start 0.7874 -0.4064)
			(end 0.7874 0.4064)
			(stroke
				(width 0.1524)
				(type default)
			)
			(layer "F.SilkS")
		)
		(fp_line
			(start 0.7874 0.4064)
			(end -0.7874 0.4064)
			(stroke
				(width 0.1524)
				(type default)
			)
			(layer "F.SilkS")
		)
		(fp_line
			(start -0.67945 -0.305054)
			(end -0.12065 -0.305054)
			(stroke
				(width 0.1)
				(type default)
			)
			(layer "F.Fab")
		)
		(fp_line
			(start -0.67945 0.3048)
			(end -0.67945 -0.305054)
			(stroke
				(width 0.1)
				(type default)
			)
			(layer "F.Fab")
		)
		(fp_line
			(start -0.12065 -0.305054)
			(end -0.12065 -0.2794)
			(stroke
				(width 0.1)
				(type default)
			)
			(layer "F.Fab")
		)
		(fp_line
			(start -0.12065 -0.2794)
			(end 0.12065 -0.2794)
			(stroke
				(width 0.1)
				(type default)
			)
			(layer "F.Fab")
		)
		(fp_line
			(start -0.12065 0.2794)
			(end -0.12065 0.3048)
			(stroke
				(width 0.1)
				(type default)
			)
			(layer "F.Fab")
		)
		(fp_line
			(start -0.12065 0.3048)
			(end -0.67945 0.3048)
			(stroke
				(width 0.1)
				(type default)
			)
			(layer "F.Fab")
		)
		(fp_line
			(start 0.120396 0.2794)
			(end -0.12065 0.2794)
			(stroke
				(width 0.1)
				(type default)
			)
			(layer "F.Fab")
		)
		(fp_line
			(start 0.120396 0.3048)
			(end 0.120396 0.2794)
			(stroke
				(width 0.1)
				(type default)
			)
			(layer "F.Fab")
		)
		(fp_line
			(start 0.12065 -0.3048)
			(end 0.67945 -0.3048)
			(stroke
				(width 0.1)
				(type default)
			)
			(layer "F.Fab")
		)
		(fp_line
			(start 0.12065 -0.2794)
			(end 0.12065 -0.3048)
			(stroke
				(width 0.1)
				(type default)
			)
			(layer "F.Fab")
		)
		(fp_line
			(start 0.67945 -0.3048)
			(end 0.67945 0.3048)
			(stroke
				(width 0.1)
				(type default)
			)
			(layer "F.Fab")
		)
		(fp_line
			(start 0.67945 0.3048)
			(end 0.120396 0.3048)
			(stroke
				(width 0.1)
				(type default)
			)
			(layer "F.Fab")
		)
		(pad "1" smd circle
			(at -0.40005 0)
			(size 0 0)
			(layers "F.Cu" "F.Mask" "F.Paste")
			(net "P1V05_PCH_AUX")
		)
		(pad "2" smd circle
			(at 0.40005 0)
			(size 0 0)
			(layers "F.Cu" "F.Mask" "F.Paste")
			(net "FAB_REV_ID2")
		)
	)
	(footprint ""
		(layer "F.Cu")
		(at 179.360068 -397.188182)
		(property "Reference" "PR3930"
			(at 0 0 0)
			(layer "F.SilkS")
			(hide yes)
			(effects
				(font
					(size 1.27 1.27)
				)
			)
		)
		(property "Value" ""
			(at 0 0 0)
			(layer "F.Fab")
			(effects
				(font
					(size 1.27 1.27)
				)
			)
		)
		(duplicate_pad_numbers_are_jumpers no)
		(fp_line
			(start -0.7874 -0.4064)
			(end 0.7874 -0.4064)
			(stroke
				(width 0.1524)
				(type default)
			)
			(layer "F.SilkS")
		)
		(fp_line
			(start -0.7874 0.4064)
			(end -0.7874 -0.4064)
			(stroke
				(width 0.1524)
				(type default)
			)
			(layer "F.SilkS")
		)
		(fp_line
			(start 0.7874 -0.4064)
			(end 0.7874 0.4064)
			(stroke
				(width 0.1524)
				(type default)
			)
			(layer "F.SilkS")
		)
		(fp_line
			(start 0.7874 0.4064)
			(end -0.7874 0.4064)
			(stroke
				(width 0.1524)
				(type default)
			)
			(layer "F.SilkS")
		)
		(fp_line
			(start -0.67945 -0.305054)
			(end -0.12065 -0.305054)
			(stroke
				(width 0.1)
				(type default)
			)
			(layer "F.Fab")
		)
		(fp_line
			(start -0.67945 0.3048)
			(end -0.67945 -0.305054)
			(stroke
				(width 0.1)
				(type default)
			)
			(layer "F.Fab")
		)
		(fp_line
			(start -0.12065 -0.305054)
			(end -0.12065 -0.2794)
			(stroke
				(width 0.1)
				(type default)
			)
			(layer "F.Fab")
		)
		(fp_line
			(start -0.12065 -0.2794)
			(end 0.12065 -0.2794)
			(stroke
				(width 0.1)
				(type default)
			)
			(layer "F.Fab")
		)
		(fp_line
			(start -0.12065 0.2794)
			(end -0.12065 0.3048)
			(stroke
				(width 0.1)
				(type default)
			)
			(layer "F.Fab")
		)
		(fp_line
			(start -0.12065 0.3048)
			(end -0.67945 0.3048)
			(stroke
				(width 0.1)
				(type default)
			)
			(layer "F.Fab")
		)
		(fp_line
			(start 0.120396 0.2794)
			(end -0.12065 0.2794)
			(stroke
				(width 0.1)
				(type default)
			)
			(layer "F.Fab")
		)
		(fp_line
			(start 0.120396 0.3048)
			(end 0.120396 0.2794)
			(stroke
				(width 0.1)
				(type default)
			)
			(layer "F.Fab")
		)
		(fp_line
			(start 0.12065 -0.3048)
			(end 0.67945 -0.3048)
			(stroke
				(width 0.1)
				(type default)
			)
			(layer "F.Fab")
		)
		(fp_line
			(start 0.12065 -0.2794)
			(end 0.12065 -0.3048)
			(stroke
				(width 0.1)
				(type default)
			)
			(layer "F.Fab")
		)
		(fp_line
			(start 0.67945 -0.3048)
			(end 0.67945 0.3048)
			(stroke
				(width 0.1)
				(type default)
			)
			(layer "F.Fab")
		)
		(fp_line
			(start 0.67945 0.3048)
			(end 0.120396 0.3048)
			(stroke
				(width 0.1)
				(type default)
			)
			(layer "F.Fab")
		)
		(pad "1" smd circle
			(at -0.40005 0)
			(size 0 0)
			(layers "F.Cu" "F.Mask" "F.Paste")
			(net "AGND_HSC")
		)
		(pad "2" smd circle
			(at 0.40005 0)
			(size 0 0)
			(layers "F.Cu" "F.Mask" "F.Paste")
			(net "HSC_ADDR")
		)
	)
)
